# TIMECARD (Time Appliance Project (Time Card)) — schematic netlist excerpt (pin names and nets, part order shuffled) for the footprints in the layout excerpt that follows; sources: Cadence DE-HDL packaged netlist, KiCad conversion of R4006-B0001-02_R01.brd

C27  CAPACITOR  0.1UF 10%  pkg SMC_0402R_H022  page 9 : \1\ = C_CPU_RX_PCIE_MGT1_TXN ; \2\ = CPU_RX_PCIE_MGT1_TXN
R263  RESISTOR  0OHM -  pkg SMC_0402R_H016  page 28 : \1\ = R_XP3R3V_PG ; \2\ = XP3R3V_PG

(kicad_pcb
	(version 20260206)
	(generator "pcbnew")
	(generator_version "10.0")
	(general
		(thickness 1.6)
		(legacy_teardrops no)
	)
	(paper "A4")
	(title_block
		(title "timecard-production-celestica-r4006 — R4006-B0001-02_R01.brd")
		(comment 1 "Time Appliance Project (Time Card) / footprints 1017-1018 of 1113")
	)
	(layers
		(0 "F.Cu" signal "TOP")
		(4 "In1.Cu" signal "L02_GND1")
		(6 "In2.Cu" signal "L03_SIG1")
		(8 "In3.Cu" signal "L04_GND2")
		(10 "In4.Cu" signal "L05_VCC1")
		(12 "In5.Cu" signal "L06_VCC2")
		(14 "In6.Cu" signal "L07_GND3")
		(16 "In7.Cu" signal "L08_SIG2")
		(18 "In8.Cu" signal "L09_GND4")
		(2 "B.Cu" signal "BOTTOM")
		(9 "F.Adhes" user "F.Adhesive")
		(11 "B.Adhes" user "B.Adhesive")
		(13 "F.Paste" user "Package Geometry/Pastemask Top")
		(15 "B.Paste" user "Package Geometry/Pastemask Bottom")
		(5 "F.SilkS" user "Ref Des/Silkscreen Top")
		(7 "B.SilkS" user "Ref Des/Silkscreen Bottom")
		(1 "F.Mask" user "Board Geometry/Soldermask Top")
		(3 "B.Mask" user "Board Geometry/Soldermask Bottom")
		(17 "Dwgs.User" user "User.Drawings")
		(19 "Cmts.User" user "User.Comments")
		(21 "Eco1.User" user "User.Eco1")
		(23 "Eco2.User" user "User.Eco2")
		(25 "Edge.Cuts" user "Board Geometry/Outline")
		(27 "Margin" user)
		(31 "F.CrtYd" user "Package Geometry/Place Bound Top")
		(29 "B.CrtYd" user "Package Geometry/Place Bound Bottom")
		(35 "F.Fab" user "Ref Des/Assembly Top")
		(33 "B.Fab" user "Ref Des/Assembly Bottom")
	)
	(footprint ""
		(layer "B.Cu")
		(at 90.7542 -106.6038 180)
		(property "Reference" "R263"
			(at 0.5842 2.19583 0)
			(unlocked yes)
			(layer "B.SilkS")
			(effects
				(font
					(size 0.7874 0.5842)
					(thickness 0.1524)
				)
				(justify mirror)
			)
		)
		(property "Value" "VAL*"
			(at -0.02032 2.13233 180)
			(unlocked yes)
			(layer "B.Fab")
			(hide yes)
			(effects
				(font
					(size 0.7874 0.5842)
					(thickness 0.1524)
				)
				(justify mirror)
			)
		)
		(property "Tolerance" "TOL*"
			(at -0.044704 3.05435 180)
			(unlocked yes)
			(layer "Cmts.User")
			(hide yes)
			(effects
				(font
					(size 0.7874 0.5842)
					(thickness 0.1524)
				)
				(justify mirror)
			)
		)
		(property "User Part Number" "PARTNUM*"
			(at -0.02032 4.024884 180)
			(unlocked yes)
			(layer "Cmts.User")
			(hide yes)
			(effects
				(font
					(size 0.7874 0.5842)
					(thickness 0.1524)
				)
				(justify mirror)
			)
		)
		(property "Device Type" "RESISTOR-G155-100R0-J0,0OHM,-"
			(at -0.008382 1.210564 180)
			(unlocked yes)
			(layer "B.Fab")
			(hide yes)
			(effects
				(font
					(size 0.7874 0.5842)
					(thickness 0.1524)
				)
				(justify mirror)
			)
		)
		(duplicate_pad_numbers_are_jumpers no)
		(fp_line
			(start 1.143 0.5588)
			(end -1.143 0.5588)
			(stroke
				(width 0.1)
				(type default)
			)
			(layer "B.SilkS")
		)
		(fp_line
			(start 1.143 -0.5588)
			(end 1.143 0.5588)
			(stroke
				(width 0.1)
				(type default)
			)
			(layer "B.SilkS")
		)
		(fp_line
			(start -1.143 0.5588)
			(end -1.143 -0.5588)
			(stroke
				(width 0.1)
				(type default)
			)
			(layer "B.SilkS")
		)
		(fp_line
			(start -1.143 -0.5588)
			(end 1.143 -0.5588)
			(stroke
				(width 0.1)
				(type default)
			)
			(layer "B.SilkS")
		)
		(fp_rect
			(start -1.143 0.5588)
			(end 1.143 -0.5588)
			(stroke
				(width 0)
				(type default)
			)
			(fill no)
			(layer "B.CrtYd")
		)
		(fp_line
			(start 0.508 0.3048)
			(end -0.508 0.3048)
			(stroke
				(width 0.1)
				(type default)
			)
			(layer "B.Fab")
		)
		(fp_line
			(start 0.508 -0.3048)
			(end 0.508 0.3048)
			(stroke
				(width 0.1)
				(type default)
			)
			(layer "B.Fab")
		)
		(fp_line
			(start -0.508 0.3048)
			(end -0.508 -0.3048)
			(stroke
				(width 0.1)
				(type default)
			)
			(layer "B.Fab")
		)
		(fp_line
			(start -0.508 -0.3048)
			(end 0.508 -0.3048)
			(stroke
				(width 0.1)
				(type default)
			)
			(layer "B.Fab")
		)
		(pad "1" smd rect
			(at 0.5334 0)
			(size 0.7112 0.6096)
			(layers "B.Cu" "B.Mask" "B.Paste")
			(net "R_XP3R3V_PG")
		)
		(pad "2" smd rect
			(at -0.5334 0)
			(size 0.7112 0.6096)
			(layers "B.Cu" "B.Mask" "B.Paste")
			(net "XP3R3V_PG")
		)
		(zone
			(layer "B.Cu")
			(hatch none 0.5)
			(connect_pads
				(clearance 0)
			)
			(min_thickness 0.25)
			(keepout
				(tracks allowed)
				(vias not_allowed)
				(pads allowed)
				(copperpour not_allowed)
				(footprints allowed)
			)
			(placement
				(enabled no)
				(sheetname "")
			)
			(fill
				(thermal_gap 0.5)
				(thermal_bridge_width 0.5)
				(island_removal_mode 0)
			)
			(polygon
				(pts
					(xy 90.8304 -106.9086) (xy 90.678 -106.9086) (xy 90.678 -106.299) (xy 90.8304 -106.299)
				)
			)
		)
	)
	(footprint ""
		(layer "B.Cu")
		(at 68.784978 -15.367 -90)
		(property "Reference" "C27"
			(at 3.048 -0.144272 270)
			(unlocked yes)
			(layer "B.SilkS")
			(effects
				(font
					(size 0.635 0.4064)
					(thickness 0.1524)
				)
				(justify mirror)
			)
		)
		(property "Value" "VAL*"
			(at -0.0762 2.067306 270)
			(unlocked yes)
			(layer "B.Fab")
			(hide yes)
			(effects
				(font
					(size 0.7874 0.5842)
					(thickness 0.1524)
				)
				(justify mirror)
			)
		)
		(property "Tolerance" "TOL*"
			(at -0.0762 3.032506 270)
			(unlocked yes)
			(layer "Cmts.User")
			(hide yes)
			(effects
				(font
					(size 0.7874 0.5842)
					(thickness 0.1524)
				)
				(justify mirror)
			)
		)
		(property "User Part Number" "PARTNUM*"
			(at -0.1016 4.023106 270)
			(unlocked yes)
			(layer "Cmts.User")
			(hide yes)
			(effects
				(font
					(size 0.7874 0.5842)
					(thickness 0.1524)
				)
				(justify mirror)
			)
		)
		(property "Device Type" "CAPACITOR-G105-0B104-CK,0.1UF,A"
			(at -0.0508 1.127506 270)
			(unlocked yes)
			(layer "B.Fab")
			(hide yes)
			(effects
				(font
					(size 0.7874 0.5842)
					(thickness 0.1524)
				)
				(justify mirror)
			)
		)
		(duplicate_pad_numbers_are_jumpers no)
		(fp_line
			(start -1.143 0.5588)
			(end -1.143 -0.5588)
			(stroke
				(width 0.1)
				(type default)
			)
			(layer "B.SilkS")
		)
		(fp_line
			(start 1.143 0.5588)
			(end -1.143 0.5588)
			(stroke
				(width 0.1)
				(type default)
			)
			(layer "B.SilkS")
		)
		(fp_line
			(start -1.143 -0.5588)
			(end 1.143 -0.5588)
			(stroke
				(width 0.1)
				(type default)
			)
			(layer "B.SilkS")
		)
		(fp_line
			(start 1.143 -0.5588)
			(end 1.143 0.5588)
			(stroke
				(width 0.1)
				(type default)
			)
			(layer "B.SilkS")
		)
		(fp_rect
			(start 1.143 0.5588)
			(end -1.143 -0.5588)
			(stroke
				(width 0)
				(type default)
			)
			(fill no)
			(layer "B.CrtYd")
		)
		(fp_line
			(start -0.508 0.3048)
			(end -0.508 -0.3048)
			(stroke
				(width 0.1)
				(type default)
			)
			(layer "B.Fab")
		)
		(fp_line
			(start 0.508 0.3048)
			(end -0.508 0.3048)
			(stroke
				(width 0.1)
				(type default)
			)
			(layer "B.Fab")
		)
		(fp_line
			(start -0.508 -0.3048)
			(end 0.508 -0.3048)
			(stroke
				(width 0.1)
				(type default)
			)
			(layer "B.Fab")
		)
		(fp_line
			(start 0.508 -0.3048)
			(end 0.508 0.3048)
			(stroke
				(width 0.1)
				(type default)
			)
			(layer "B.Fab")
		)
		(pad "1" smd rect
			(at 0.5334 0 90)
			(size 0.7112 0.6096)
			(layers "B.Cu" "B.Mask" "B.Paste")
			(net "C_CPU_RX_PCIE_MGT1_TXN")
		)
		(pad "2" smd rect
			(at -0.5334 0 90)
			(size 0.7112 0.6096)
			(layers "B.Cu" "B.Mask" "B.Paste")
			(net "CPU_RX_PCIE_MGT1_TXN")
		)
		(zone
			(layer "B.Cu")
			(hatch none 0.5)
			(connect_pads
				(clearance 0)
			)
			(min_thickness 0.25)
			(keepout
				(tracks allowed)
				(vias not_allowed)
				(pads allowed)
				(copperpour not_allowed)
				(footprints allowed)
			)
			(placement
				(enabled no)
				(sheetname "")
			)
			(fill
				(thermal_gap 0.5)
				(thermal_bridge_width 0.5)
				(island_removal_mode 0)
			)
			(polygon
				(pts
					(xy 68.480178 -15.2908) (xy 69.089778 -15.2908) (xy 69.089778 -15.4432) (xy 68.480178 -15.4432)
				)
			)
		)
	)
)
